FILE_TYPE=LIBRARY_PARTS;
primitive '74LVC1G07GW';
  pin
    'VCC':
      PIN_NUMBER='(5)';
      PINUSE='POWER';
      NO_LOAD_CHECK='Both';
      NO_IO_CHECK='Both';
      NO_ASSERT_CHECK='TRUE';
      NO_DIR_CHECK='TRUE';
      ALLOW_CONNECT='TRUE';
    'A':
      PIN_NUMBER='(2)';
      INPUT_LOAD='(-0.01,0.01)';
    'GND':
      PIN_NUMBER='(3)';
      PINUSE='POWER';
      NO_LOAD_CHECK='Both';
      NO_IO_CHECK='Both';
      NO_ASSERT_CHECK='TRUE';
      NO_DIR_CHECK='TRUE';
      ALLOW_CONNECT='TRUE';
    'Y':
      PIN_NUMBER='(4)';
      OUTPUT_TYPE='(OC,AND)';
      OUTPUT_LOAD='(1.0,*)';
    'NC':
      PIN_NUMBER='(1)';
      OUTPUT_TYPE='(TS,TS)';
      INPUT_LOAD='(-0.01,0.01)';
      OUTPUT_LOAD='(1.0,-1.0)';
  end_pin;
  body
    PART_NAME='74LVC1G07GW';
    BODY_NAME='74LVC1G07GW';
    PHYS_DES_PREFIX='U';
    CLASS='IC';
  end_body;
end_primitive;

END.
